(kicad_pcb
	(version 20260206)
	(generator "pcbnew")
	(generator_version "10.0")
	(general
		(thickness 1.6)
		(legacy_teardrops no)
	)
	(paper "A4")
	(title_block
		(title "Bryce Canyon_R.DPB_16317-1_OCP.brd")
		(comment 1 "Bryce Canyon / footprints 1606-1609 of 2099")
	)
	(layers
		(0 "F.Cu" signal "TOP")
		(4 "In1.Cu" signal "L2GND")
		(6 "In2.Cu" signal "L3")
		(8 "In3.Cu" signal "L4VCC")
		(10 "In4.Cu" signal "L5VCC")
		(12 "In5.Cu" signal "L6")
		(14 "In6.Cu" signal "L7GND")
		(2 "B.Cu" signal "BOTTOM")
		(9 "F.Adhes" user "F.Adhesive")
		(11 "B.Adhes" user "B.Adhesive")
		(13 "F.Paste" user "Package Geometry/Pastemask Top")
		(15 "B.Paste" user "Package Geometry/Pastemask Bottom")
		(5 "F.SilkS" user "Ref Des/Silkscreen Top")
		(7 "B.SilkS" user "Ref Des/Silkscreen Bottom")
		(1 "F.Mask" user "Board Geometry/Soldermask Top")
		(3 "B.Mask" user "Board Geometry/Soldermask Bottom")
		(17 "Dwgs.User" user "User.Drawings")
		(19 "Cmts.User" user "User.Comments")
		(21 "Eco1.User" user "User.Eco1")
		(23 "Eco2.User" user "User.Eco2")
		(25 "Edge.Cuts" user "Board Geometry/Outline")
		(27 "Margin" user)
		(31 "F.CrtYd" user "Package Geometry/Place Bound Top")
		(29 "B.CrtYd" user "Package Geometry/Place Bound Bottom")
		(35 "F.Fab" user "Ref Des/Assembly Top")
		(33 "B.Fab" user "Ref Des/Assembly Bottom")
	)
	(footprint ""
		(layer "F.Cu")
		(at 154.399996 -28.910026 -90)
		(property "Reference" "HDDSAS28"
			(at 0 0 270)
			(layer "F.SilkS")
			(hide yes)
			(effects
				(font
					(size 1.27 1.27)
				)
			)
		)
		(property "Value" "SKT-SAS15P-14P-45-GP"
			(at -20.7645 -8.9789 270)
			(unlocked yes)
			(layer "F.Fab")
			(hide yes)
			(effects
				(font
					(size 1.016 1.016)
					(thickness 0.1524)
				)
			)
		)
		(property "Device Type" "10120818-001C-TRLF"
			(at -20.7645 -10.5029 270)
			(unlocked yes)
			(layer "F.Fab")
			(hide yes)
			(effects
				(font
					(size 1.016 1.016)
					(thickness 0.1524)
				)
			)
		)
		(duplicate_pad_numbers_are_jumpers no)
		(fp_line
			(start 1.651 4.2926)
			(end 1.651 3.0099)
			(stroke
				(width 0.1524)
				(type default)
			)
			(layer "F.SilkS")
		)
		(fp_line
			(start 8.509 4.2926)
			(end 1.651 4.2926)
			(stroke
				(width 0.1524)
				(type default)
			)
			(layer "F.SilkS")
		)
		(fp_line
			(start -23.4188 3.0099)
			(end -23.4188 -3.2512)
			(stroke
				(width 0.1524)
				(type default)
			)
			(layer "F.SilkS")
		)
		(fp_line
			(start 1.651 3.0099)
			(end -23.4188 3.0099)
			(stroke
				(width 0.1524)
				(type default)
			)
			(layer "F.SilkS")
		)
		(fp_line
			(start 8.509 3.0099)
			(end 8.509 4.2926)
			(stroke
				(width 0.1524)
				(type default)
			)
			(layer "F.SilkS")
		)
		(fp_line
			(start 23.4188 3.0099)
			(end 8.509 3.0099)
			(stroke
				(width 0.1524)
				(type default)
			)
			(layer "F.SilkS")
		)
		(fp_line
			(start -23.4188 -3.2512)
			(end 23.4188 -3.2512)
			(stroke
				(width 0.1524)
				(type default)
			)
			(layer "F.SilkS")
		)
		(fp_line
			(start 23.4188 -3.2512)
			(end 23.4188 3.0099)
			(stroke
				(width 0.1524)
				(type default)
			)
			(layer "F.SilkS")
		)
		(fp_line
			(start 15.5067 -3.3401)
			(end 16.2687 -3.3401)
			(stroke
				(width 0.3302)
				(type default)
			)
			(layer "F.SilkS")
		)
		(fp_poly
			(pts
				(xy 15.868904 -3.230372) (xy 16.503904 -3.865372) (xy 15.233904 -3.865372)
			)
			(stroke
				(width 0)
				(type default)
			)
			(fill yes)
			(layer "F.SilkS")
		)
		(fp_poly
			(pts
				(xy -22.8727 -2.7559) (xy 22.8727 -2.7559) (xy 22.8727 2.7559) (xy 8.255 2.7559) (xy 8.255 3.5179)
				(xy 1.905 3.5179) (xy 1.905 2.7559) (xy -22.8727 2.7559)
			)
			(stroke
				(width 0)
				(type default)
			)
			(fill no)
			(layer "F.CrtYd")
		)
		(fp_poly
			(pts
				(xy 1.397 4.5466) (xy 1.397 3.2639) (xy -23.6728 3.2639) (xy -23.6728 -3.5052) (xy 23.6728 -3.5052)
				(xy 23.6728 -0.00635) (xy 22.8727 -0.00635) (xy 22.8727 -2.7559) (xy -22.8727 -2.7559) (xy -22.8727 2.7559)
				(xy 1.905 2.7559) (xy 1.905 3.5179) (xy 8.255 3.5179) (xy 8.255 2.7559) (xy 22.8727 2.7559) (xy 22.8727 0.00635)
				(xy 23.6728 0.00635) (xy 23.6728 3.2639) (xy 8.763 3.2639) (xy 8.763 4.5466)
			)
			(stroke
				(width 0)
				(type default)
			)
			(fill no)
			(layer "F.CrtYd")
		)
		(fp_poly
			(pts
				(xy 1.397 4.5466) (xy 1.397 3.2639) (xy -23.6728 3.2639) (xy -23.6728 -3.5052) (xy 23.6728 -3.5052)
				(xy 23.6728 3.2639) (xy 8.763 3.2639) (xy 8.763 4.5466)
			)
			(stroke
				(width 0)
				(type default)
			)
			(fill no)
			(layer "F.Fab")
		)
		(pad "" np_thru_hole circle
			(at -18.874994 0 270)
			(size 0.254 0.254)
			(drill 1.3462)
			(layers "*.Cu" "*.Mask")
			(clearance 0.9017)
			(thermal_gap 0.9017)
		)
		(pad "" np_thru_hole circle
			(at 18.874994 0 270)
			(size 0.254 0.254)
			(drill 0.9398)
			(layers "*.Cu" "*.Mask")
			(clearance 0.6985)
			(thermal_gap 0.6985)
		)
		(pad "G1" smd rect
			(at 21.874988 0 270)
			(size 2.5908 2.5908)
			(layers "F.Cu" "F.Mask" "F.Paste")
			(net "GND")
		)
		(pad "G2" smd rect
			(at -21.874988 0 270)
			(size 2.5908 2.5908)
			(layers "F.Cu" "F.Mask" "F.Paste")
			(net "GND")
		)
		(pad "P1" smd rect
			(at 1.905 -1.82499 270)
			(size 0.6096 2.3622)
			(layers "F.Cu" "F.Mask" "F.Paste")
			(net "Net_1659")
		)
		(pad "P2" smd rect
			(at 0.635 -1.82499 270)
			(size 0.6096 2.3622)
			(layers "F.Cu" "F.Mask" "F.Paste")
			(net "Net_1660")
		)
		(pad "P3" smd rect
			(at -0.635 -1.82499 270)
			(size 0.6096 2.3622)
			(layers "F.Cu" "F.Mask" "F.Paste")
			(net "Net_1661")
		)
		(pad "P4" smd rect
			(at -1.905 -1.82499 270)
			(size 0.6096 2.3622)
			(layers "F.Cu" "F.Mask" "F.Paste")
			(net "GND")
		)
		(pad "P5" smd rect
			(at -3.175 -1.82499 270)
			(size 0.6096 2.3622)
			(layers "F.Cu" "F.Mask" "F.Paste")
			(net "HDD_PRSNT_28")
		)
		(pad "P6" smd rect
			(at -4.445 -1.82499 270)
			(size 0.6096 2.3622)
			(layers "F.Cu" "F.Mask" "F.Paste")
			(net "GND")
		)
		(pad "P7" smd rect
			(at -5.715 -1.82499 270)
			(size 0.6096 2.3622)
			(layers "F.Cu" "F.Mask" "F.Paste")
			(net "5V_PRE_28")
		)
		(pad "P8" smd rect
			(at -6.985 -1.82499 270)
			(size 0.6096 2.3622)
			(layers "F.Cu" "F.Mask" "F.Paste")
			(net "P5V_HDD28")
		)
		(pad "P9" smd rect
			(at -8.255 -1.82499 270)
			(size 0.6096 2.3622)
			(layers "F.Cu" "F.Mask" "F.Paste")
			(net "P5V_HDD28")
		)
		(pad "P10" smd rect
			(at -9.525 -1.82499 270)
			(size 0.6096 2.3622)
			(layers "F.Cu" "F.Mask" "F.Paste")
			(net "GND")
		)
		(pad "P11" smd rect
			(at -10.795 -1.82499 270)
			(size 0.6096 2.3622)
			(layers "F.Cu" "F.Mask" "F.Paste")
			(net "ACT_HDD_28")
		)
		(pad "P12" smd rect
			(at -12.065 -1.82499 270)
			(size 0.6096 2.3622)
			(layers "F.Cu" "F.Mask" "F.Paste")
			(net "GND")
		)
		(pad "P13" smd rect
			(at -13.335 -1.82499 270)
			(size 0.6096 2.3622)
			(layers "F.Cu" "F.Mask" "F.Paste")
			(net "12V_PRE_28")
		)
		(pad "P14" smd rect
			(at -14.605 -1.82499 270)
			(size 0.6096 2.3622)
			(layers "F.Cu" "F.Mask" "F.Paste")
			(net "P12V_HDD28")
		)
		(pad "P15" smd rect
			(at -15.875 -1.82499 270)
			(size 0.6096 2.3622)
			(layers "F.Cu" "F.Mask" "F.Paste")
			(net "P12V_HDD28")
		)
		(pad "S1" smd rect
			(at 15.875 -1.82499 270)
			(size 0.6096 2.3622)
			(layers "F.Cu" "F.Mask" "F.Paste")
			(net "GND")
		)
		(pad "S2" smd rect
			(at 14.605 -1.82499 270)
			(size 0.6096 2.3622)
			(layers "F.Cu" "F.Mask" "F.Paste")
			(net "SAS_HDD_RX_P28")
		)
		(pad "S3" smd rect
			(at 13.335 -1.82499 270)
			(size 0.6096 2.3622)
			(layers "F.Cu" "F.Mask" "F.Paste")
			(net "SAS_HDD_RX_N28")
		)
		(pad "S4" smd rect
			(at 12.065 -1.82499 270)
			(size 0.6096 2.3622)
			(layers "F.Cu" "F.Mask" "F.Paste")
			(net "GND")
		)
		(pad "S5" smd rect
			(at 10.795 -1.82499 270)
			(size 0.6096 2.3622)
			(layers "F.Cu" "F.Mask" "F.Paste")
			(net "PHY_DRV_B_TO_SCC_B_28_DN")
		)
		(pad "S6" smd rect
			(at 9.525 -1.82499 270)
			(size 0.6096 2.3622)
			(layers "F.Cu" "F.Mask" "F.Paste")
			(net "PHY_DRV_B_TO_SCC_B_28_DP")
		)
		(pad "S7" smd rect
			(at 8.255 -1.82499 270)
			(size 0.6096 2.3622)
			(layers "F.Cu" "F.Mask" "F.Paste")
			(net "GND")
		)
		(pad "S8" smd rect
			(at 7.480046 2.845054 270)
			(size 0.508 2.3622)
			(layers "F.Cu" "F.Mask" "F.Paste")
			(net "GND")
		)
		(pad "S9" smd rect
			(at 6.679946 2.845054 270)
			(size 0.508 2.3622)
			(layers "F.Cu" "F.Mask" "F.Paste")
			(net "Net_452")
		)
		(pad "S10" smd rect
			(at 5.8801 2.845054 270)
			(size 0.508 2.3622)
			(layers "F.Cu" "F.Mask" "F.Paste")
			(net "Net_344")
		)
		(pad "S11" smd rect
			(at 5.08 2.845054 270)
			(size 0.508 2.3622)
			(layers "F.Cu" "F.Mask" "F.Paste")
			(net "GND")
		)
		(pad "S12" smd rect
			(at 4.2799 2.845054 270)
			(size 0.508 2.3622)
			(layers "F.Cu" "F.Mask" "F.Paste")
			(net "Net_380")
		)
		(pad "S13" smd rect
			(at 3.480054 2.845054 270)
			(size 0.508 2.3622)
			(layers "F.Cu" "F.Mask" "F.Paste")
			(net "Net_416")
		)
		(pad "S14" smd rect
			(at 2.679954 2.845054 270)
			(size 0.508 2.3622)
			(layers "F.Cu" "F.Mask" "F.Paste")
			(net "GND")
		)
		(zone
			(layer "F.Cu")
			(hatch none 0.5)
			(connect_pads
				(clearance 0)
			)
			(min_thickness 0.25)
			(keepout
				(tracks not_allowed)
				(vias allowed)
				(pads allowed)
				(copperpour not_allowed)
				(footprints allowed)
			)
			(placement
				(enabled no)
				(sheetname "")
			)
			(fill
				(thermal_gap 0.5)
				(thermal_bridge_width 0.5)
				(island_removal_mode 0)
			)
			(polygon
				(pts
					(xy 158.057596 -45.648626) (xy 150.983696 -45.648626) (xy 150.983696 -52.582826) (xy 152.088596 -52.582826)
					(xy 152.088596 -48.468026) (xy 156.711396 -48.468026) (xy 156.711396 -52.582826) (xy 158.057596 -52.582826)
				)
			)
		)
		(zone
			(layer "F.Cu")
			(hatch none 0.5)
			(connect_pads
				(clearance 0)
			)
			(min_thickness 0.25)
			(keepout
				(tracks allowed)
				(vias not_allowed)
				(pads allowed)
				(copperpour not_allowed)
				(footprints allowed)
			)
			(placement
				(enabled no)
				(sheetname "")
			)
			(fill
				(thermal_gap 0.5)
				(thermal_bridge_width 0.5)
				(island_removal_mode 0)
			)
			(polygon
				(pts
					(xy 158.057596 -45.648626) (xy 150.983696 -45.648626) (xy 150.983696 -52.582826) (xy 152.088596 -52.582826)
					(xy 152.088596 -48.468026) (xy 156.711396 -48.468026) (xy 156.711396 -52.582826) (xy 158.057596 -52.582826)
				)
			)
		)
		(zone
			(layer "F.Cu")
			(hatch none 0.5)
			(connect_pads
				(clearance 0)
			)
			(min_thickness 0.25)
			(keepout
				(tracks allowed)
				(vias not_allowed)
				(pads allowed)
				(copperpour not_allowed)
				(footprints allowed)
			)
			(placement
				(enabled no)
				(sheetname "")
			)
			(fill
				(thermal_gap 0.5)
				(thermal_bridge_width 0.5)
				(island_removal_mode 0)
			)
			(polygon
				(pts
					(xy 158.057596 -12.171426) (xy 150.983696 -12.171426) (xy 150.983696 -5.237226) (xy 152.088596 -5.237226)
					(xy 152.088596 -9.352026) (xy 156.711396 -9.352026) (xy 156.711396 -5.237226) (xy 158.057596 -5.237226)
				)
			)
		)
		(zone
			(layer "F.Cu")
			(hatch none 0.5)
			(connect_pads
				(clearance 0)
			)
			(min_thickness 0.25)
			(keepout
				(tracks not_allowed)
				(vias allowed)
				(pads allowed)
				(copperpour not_allowed)
				(footprints allowed)
			)
			(placement
				(enabled no)
				(sheetname "")
			)
			(fill
				(thermal_gap 0.5)
				(thermal_bridge_width 0.5)
				(island_removal_mode 0)
			)
			(polygon
				(pts
					(xy 158.057596 -12.171426) (xy 150.983696 -12.171426) (xy 150.983696 -5.237226) (xy 152.088596 -5.237226)
					(xy 152.088596 -9.352026) (xy 156.711396 -9.352026) (xy 156.711396 -5.237226) (xy 158.057596 -5.237226)
				)
			)
		)
		(zone
			(layers "F.Cu" "B.Cu" "In1.Cu" "In2.Cu" "In3.Cu" "In4.Cu" "In5.Cu" "In6.Cu")
			(hatch none 0.5)
			(connect_pads
				(clearance 0)
			)
			(min_thickness 0.25)
			(keepout
				(tracks not_allowed)
				(vias allowed)
				(pads allowed)
				(copperpour not_allowed)
				(footprints allowed)
			)
			(placement
				(enabled no)
				(sheetname "")
			)
			(fill
				(thermal_gap 0.5)
				(thermal_bridge_width 0.5)
				(island_removal_mode 0)
			)
			(polygon
				(pts
					(arc
						(start 155.174696 -10.035032)
						(mid 153.625296 -10.035032)
						(end 155.174696 -10.035032)
					)
				)
			)
		)
		(zone
			(layers "F.Cu" "B.Cu" "In1.Cu" "In2.Cu" "In3.Cu" "In4.Cu" "In5.Cu" "In6.Cu")
			(hatch none 0.5)
			(connect_pads
				(clearance 0)
			)
			(min_thickness 0.25)
			(keepout
				(tracks not_allowed)
				(vias allowed)
				(pads allowed)
				(copperpour not_allowed)
				(footprints allowed)
			)
			(placement
				(enabled no)
				(sheetname "")
			)
			(fill
				(thermal_gap 0.5)
				(thermal_bridge_width 0.5)
				(island_removal_mode 0)
			)
			(polygon
				(pts
					(arc
						(start 155.377896 -47.78502)
						(mid 153.422096 -47.78502)
						(end 155.377896 -47.78502)
					)
				)
			)
		)
	)
	(footprint ""
		(layer "F.Cu")
		(at 436.089044 -113.677446 90)
		(property "Reference" "C675"
			(at 0 0 90)
			(layer "F.SilkS")
			(hide yes)
			(effects
				(font
					(size 1.27 1.27)
				)
			)
		)
		(property "Value" "SC10U16V5KX-7-GP-U"
			(at -0.0762 -6.1214 90)
			(unlocked yes)
			(layer "F.Fab")
			(hide yes)
			(effects
				(font
					(size 1.016 1.016)
					(thickness 0.1524)
				)
			)
		)
		(property "Device Type" "C805H58"
			(at -0.0762 -8.1534 90)
			(unlocked yes)
			(layer "F.Fab")
			(hide yes)
			(effects
				(font
					(size 1.016 1.016)
					(thickness 0.1524)
				)
			)
		)
		(duplicate_pad_numbers_are_jumpers no)
		(fp_line
			(start 0.635 0)
			(end -0.635 0)
			(stroke
				(width 0.508)
				(type default)
			)
			(layer "F.SilkS")
		)
		(fp_rect
			(start -0.9652 1.778)
			(end 0.9652 -1.778)
			(stroke
				(width 0)
				(type default)
			)
			(fill no)
			(layer "F.CrtYd")
		)
		(fp_poly
			(pts
				(xy -0.9652 -1.778) (xy 0.9652 -1.778) (xy 0.9652 1.778) (xy -0.9652 1.778)
			)
			(stroke
				(width 0)
				(type default)
			)
			(fill no)
			(layer "F.Fab")
		)
		(pad "1" smd rect
			(at 0 -0.9652 90)
			(size 1.397 1.143)
			(layers "F.Cu" "F.Mask" "F.Paste")
			(net "P12V_B_4_VIN_U34")
		)
		(pad "2" smd rect
			(at 0 0.9652 90)
			(size 1.397 1.143)
			(layers "F.Cu" "F.Mask" "F.Paste")
			(net "GND")
		)
	)
	(footprint ""
		(layer "F.Cu")
		(at 81.534 -246.634)
		(property "Reference" "R203"
			(at 0 0 0)
			(layer "F.SilkS")
			(hide yes)
			(effects
				(font
					(size 1.27 1.27)
				)
			)
		)
		(property "Value" "0R2J-2-GP"
			(at 0.064008 -3.993896 0)
			(unlocked yes)
			(layer "F.Fab")
			(hide yes)
			(effects
				(font
					(size 1.016 1.016)
					(thickness 0.1524)
				)
			)
		)
		(property "Device Type" "R402H16"
			(at 0.064008 -5.517896 0)
			(unlocked yes)
			(layer "F.Fab")
			(hide yes)
			(effects
				(font
					(size 1.016 1.016)
					(thickness 0.1524)
				)
			)
		)
		(duplicate_pad_numbers_are_jumpers no)
		(fp_line
			(start -0.508 -0.9398)
			(end -0.508 0.9398)
			(stroke
				(width 0.1524)
				(type default)
			)
			(layer "F.SilkS")
		)
		(fp_line
			(start 0.508 -0.9398)
			(end -0.508 -0.9398)
			(stroke
				(width 0.1524)
				(type default)
			)
			(layer "F.SilkS")
		)
		(fp_rect
			(start -0.508 0.9398)
			(end 0.508 -0.9398)
			(stroke
				(width 0)
				(type default)
			)
			(fill no)
			(layer "F.CrtYd")
		)
		(fp_rect
			(start -0.508 0.9398)
			(end 0.508 -0.9398)
			(stroke
				(width 0)
				(type default)
			)
			(fill no)
			(layer "F.Fab")
		)
		(pad "1" smd custom
			(at 0 -0.4445)
			(size 0.1397 0.1397)
			(layers "F.Cu" "F.Mask" "F.Paste")
			(net "SW_HDD_G2")
			(options
				(clearance outline)
				(anchor circle)
			)
			(primitives
				(gr_poly
					(pts
						(arc
							(start -0.1778 -0.2794)
							(mid -0.249642 -0.249642)
							(end -0.2794 -0.1778)
						)
						(arc
							(start -0.2794 0.1778)
							(mid -0.249642 0.249642)
							(end -0.1778 0.2794)
						)
						(arc
							(start 0.1778 0.2794)
							(mid 0.249642 0.249642)
							(end 0.2794 0.1778)
						)
						(arc
							(start 0.2794 -0.1778)
							(mid 0.249642 -0.249642)
							(end 0.1778 -0.2794)
						)
					)
					(width 0)
					(fill yes)
				)
			)
		)
		(pad "2" smd custom
			(at 0 0.4445)
			(size 0.1397 0.1397)
			(layers "F.Cu" "F.Mask" "F.Paste")
			(net "SW_HDD_R2")
			(options
				(clearance outline)
				(anchor circle)
			)
			(primitives
				(gr_poly
					(pts
						(arc
							(start -0.1778 -0.2794)
							(mid -0.249642 -0.249642)
							(end -0.2794 -0.1778)
						)
						(arc
							(start -0.2794 0.1778)
							(mid -0.249642 0.249642)
							(end -0.1778 0.2794)
						)
						(arc
							(start 0.1778 0.2794)
							(mid 0.249642 0.249642)
							(end 0.2794 0.1778)
						)
						(arc
							(start 0.2794 -0.1778)
							(mid 0.249642 -0.249642)
							(end 0.1778 -0.2794)
						)
					)
					(width 0)
					(fill yes)
				)
			)
		)
	)
	(footprint ""
		(layer "F.Cu")
		(at 222.669862 -204.978 90)
		(property "Reference" "R46"
			(at 0 0 90)
			(layer "F.SilkS")
			(hide yes)
			(effects
				(font
					(size 1.27 1.27)
				)
			)
		)
		(property "Value" "4K7R2F-GP"
			(at 0.064008 -3.993896 90)
			(unlocked yes)
			(layer "F.Fab")
			(hide yes)
			(effects
				(font
					(size 1.016 1.016)
					(thickness 0.1524)
				)
			)
		)
		(property "Device Type" "R402H16"
			(at 0.064008 -5.517896 90)
			(unlocked yes)
			(layer "F.Fab")
			(hide yes)
			(effects
				(font
					(size 1.016 1.016)
					(thickness 0.1524)
				)
			)
		)
		(duplicate_pad_numbers_are_jumpers no)
		(fp_line
			(start 0.508 -0.9398)
			(end -0.508 -0.9398)
			(stroke
				(width 0.1524)
				(type default)
			)
			(layer "F.SilkS")
		)
		(fp_line
			(start -0.508 -0.9398)
			(end -0.508 0.9398)
			(stroke
				(width 0.1524)
				(type default)
			)
			(layer "F.SilkS")
		)
		(fp_rect
			(start -0.508 0.9398)
			(end 0.508 -0.9398)
			(stroke
				(width 0)
				(type default)
			)
			(fill no)
			(layer "F.CrtYd")
		)
		(fp_rect
			(start -0.508 0.9398)
			(end 0.508 -0.9398)
			(stroke
				(width 0)
				(type default)
			)
			(fill no)
			(layer "F.Fab")
		)
		(pad "1" smd custom
			(at 0 -0.4445 90)
			(size 0.1397 0.1397)
			(layers "F.Cu" "F.Mask" "F.Paste")
			(net "IO_EXP5_A1")
			(options
				(clearance outline)
				(anchor circle)
			)
			(primitives
				(gr_poly
					(pts
						(arc
							(start -0.1778 -0.2794)
							(mid -0.249642 -0.249642)
							(end -0.2794 -0.1778)
						)
						(arc
							(start -0.2794 0.1778)
							(mid -0.249642 0.249642)
							(end -0.1778 0.2794)
						)
						(arc
							(start 0.1778 0.2794)
							(mid 0.249642 0.249642)
							(end 0.2794 0.1778)
						)
						(arc
							(start 0.2794 -0.1778)
							(mid 0.249642 -0.249642)
							(end 0.1778 -0.2794)
						)
					)
					(width 0)
					(fill yes)
				)
			)
		)
		(pad "2" smd custom
			(at 0 0.4445 90)
			(size 0.1397 0.1397)
			(layers "F.Cu" "F.Mask" "F.Paste")
			(net "GND")
			(options
				(clearance outline)
				(anchor circle)
			)
			(primitives
				(gr_poly
					(pts
						(arc
							(start -0.1778 -0.2794)
							(mid -0.249642 -0.249642)
							(end -0.2794 -0.1778)
						)
						(arc
							(start -0.2794 0.1778)
							(mid -0.249642 0.249642)
							(end -0.1778 0.2794)
						)
						(arc
							(start 0.1778 0.2794)
							(mid 0.249642 0.249642)
							(end 0.2794 0.1778)
						)
						(arc
							(start 0.2794 -0.1778)
							(mid 0.249642 -0.249642)
							(end 0.1778 -0.2794)
						)
					)
					(width 0)
					(fill yes)
				)
			)
		)
	)
)
